# T6G (Grand Teton) — schematic netlist excerpt (pin names and nets, part order shuffled) for the footprints in the layout excerpt that follows; sources: Cadence DE-HDL packaged netlist, KiCad conversion of 04192023_DAF0TMB3IC0_F0TG_MB_C_brd_V02_OCP.brd

J29  SCONN288_DDR506112002KQ  IO  pkg DDR288S_1-1VXC  page 107
  VIN_BULK0  = P12V_MEM_CPU1
  RFU0  = NC
  VIN_MGMT  = P3V3_AUX
  HSCL  = I3C_SPD_DDRJ_CPU1_SCL
  HSDA  = I3C_SPD_DDRJ_CPU1_SDA
  VSS0  = GND
  DQ0_A  = M_J_CPU1_SA_DQ<0>
  VSS1  = GND
  DQ1_A  = M_J_CPU1_SA_DQ<1>
  VSS2  = GND
  DQS0_A_T  = M_J_CPU1_SA_DQS_DP<0>
  DQS0_A_C  = M_J_CPU1_SA_DQS_DN<0>
  VSS3  = GND
  DQ4_A  = M_J_CPU1_SA_DQ<4>
  VSS4  = GND
  DQ5_A  = M_J_CPU1_SA_DQ<5>
  VSS5  = GND
  DQ8_A  = M_J_CPU1_SA_DQ<8>
  VSS6  = GND
  DQ9_A  = M_J_CPU1_SA_DQ<9>
  VSS7  = GND
  DQS1_A_T  = M_J_CPU1_SA_DQS_DP<1>
  DQS1_A_C  = M_J_CPU1_SA_DQS_DN<1>
  VSS8  = GND
  DQ12_A  = M_J_CPU1_SA_DQ<12>
  VSS9  = GND
  DQ13_A  = M_J_CPU1_SA_DQ<13>
  VSS10  = GND
  DQ16_A  = M_J_CPU1_SA_DQ<16>
  VSS11  = GND
  DQ17_A  = M_J_CPU1_SA_DQ<17>
  VSS12  = GND
  DQS2_A_T  = M_J_CPU1_SA_DQS_DP<2>
  DQS2_A_C  = M_J_CPU1_SA_DQS_DN<2>
  VSS13  = GND
  DQ20_A  = M_J_CPU1_SA_DQ<20>
  VSS14  = GND
  DQ21_A  = M_J_CPU1_SA_DQ<21>
  VSS15  = GND
  DQ24_A  = M_J_CPU1_SA_DQ<24>
  VSS16  = GND
  DQ25_A  = M_J_CPU1_SA_DQ<25>
  VSS17  = GND
  DQS3_A_T  = M_J_CPU1_SA_DQS_DP<3>
  DQS3_A_C  = M_J_CPU1_SA_DQS_DN<3>
  VSS18  = GND
  DQ28_A  = M_J_CPU1_SA_DQ<28>
  VSS19  = GND
  DQ29_A  = M_J_CPU1_SA_DQ<29>
  VSS20  = GND
  CB0_A  = M_J_CPU1_SA_CB<0>
  VSS21  = GND
  CB1_A  = M_J_CPU1_SA_CB<1>
  VSS22  = GND
  DQS4_A_T  = M_J_CPU1_SA_DQS_DP<4>
  DQS4_A_C  = M_J_CPU1_SA_DQS_DN<4>
  VSS23  = GND
  CB4_A  = M_J_CPU1_SA_CB<4>
  VSS24  = GND
  CB5_A  = M_J_CPU1_SA_CB<5>
  VSS25  = GND
  ALERT_N  = M_J_CPU1_ALERT_N
  VSS26  = GND
  CS0_A_N  = M_J_CPU1_SA_CS_N<0>
  VSS27  = GND
  CA0_A  = M_J_CPU1_SA_CA<0>
  VSS28  = GND
  CA2_A  = M_J_CPU1_SA_CA<2>
  VSS29  = GND
  CA4_A  = M_J_CPU1_SA_CA<4>
  VSS30  = GND
  CA6_A  = M_J_CPU1_SA_CA<6>
  VSS31  = GND
  PAR_A  = M_J_CPU1_SA_PAR
  VSS32  = GND
  CA0_B  = M_J_CPU1_SB_CA<0>
  VSS33  = GND
  CA2_B  = M_J_CPU1_SB_CA<2>
  VSS34  = GND
  CA4_B  = M_J_CPU1_SB_CA<4>
  VSS35  = GND
  CA6_B  = M_J_CPU1_SB_CA<6>
  VSS36  = GND
  CS0_B_N  = M_J_CPU1_SB_CS_N<0>
  VSS37  = GND
  \lbd||rsp_a_n\  = M_J_CPU1_SA_RSP<0>
  \lbs||rsp_b_n\  = M_J_CPU1_SB_RSP<0>
  VSS38  = GND
  CB4_B  = M_J_CPU1_SB_CB<4>
  VSS39  = GND
  CB5_B  = M_J_CPU1_SB_CB<5>
  VSS40  = GND
  \dqs9_b_t||tdqs9_b_t||dbi4_b_n\  = M_J_CPU1_SB_DQS_DP<9>
  \dqs9_b_c||tdqs9_b_c\  = M_J_CPU1_SB_DQS_DN<9>
  VSS41  = GND
  CB0_B  = M_J_CPU1_SB_CB<0>
  VSS42  = GND
  CB1_B  = M_J_CPU1_SB_CB<1>
  VSS43  = GND
  DQ0_B  = M_J_CPU1_SB_DQ<0>
  VSS44  = GND
  DQ1_B  = M_J_CPU1_SB_DQ<1>
  VSS45  = GND
  DQS0_B_T  = M_J_CPU1_SB_DQS_DP<0>
  DQS0_B_C  = M_J_CPU1_SB_DQS_DN<0>
  VSS46  = GND
  DQ4_B  = M_J_CPU1_SB_DQ<4>
  VSS47  = GND
  DQ5_B  = M_J_CPU1_SB_DQ<5>
  VSS48  = GND
  DQ8_B  = M_J_CPU1_SB_DQ<8>
  VSS49  = GND
  DQ9_B  = M_J_CPU1_SB_DQ<9>
  VSS50  = GND
  DQS1_B_T  = M_J_CPU1_SB_DQS_DP<1>
  DQS1_B_C  = M_J_CPU1_SB_DQS_DN<1>
  VSS51  = GND
  DQ12_B  = M_J_CPU1_SB_DQ<12>
  VSS52  = GND
  DQ13_B  = M_J_CPU1_SB_DQ<13>
  VSS53  = GND
  DQ16_B  = M_J_CPU1_SB_DQ<16>
  VSS54  = GND
  DQ17_B  = M_J_CPU1_SB_DQ<17>
  VSS55  = GND
  DQS2_B_T  = M_J_CPU1_SB_DQS_DP<2>
  DQS2_B_C  = M_J_CPU1_SB_DQS_DN<2>
  VSS56  = GND
  DQ20_B  = M_J_CPU1_SB_DQ<20>
  VSS57  = GND
  DQ21_B  = M_J_CPU1_SB_DQ<21>
  VSS58  = GND
  DQ24_B  = M_J_CPU1_SB_DQ<24>
  VSS59  = GND
  DQ25_B  = M_J_CPU1_SB_DQ<25>
  VSS60  = GND
  DQS3_B_T  = M_J_CPU1_SB_DQS_DP<3>
  DQS3_B_C  = M_J_CPU1_SB_DQS_DN<3>
  VSS61  = GND
  DQ28_B  = M_J_CPU1_SB_DQ<28>
  VSS62  = GND
  DQ29_B  = M_J_CPU1_SB_DQ<29>
  VSS63  = GND
  RFU1  = NC
  VIN_BULK1  = P12V_MEM_CPU1
  VIN_BULK2  = P12V_MEM_CPU1
  \pwr_good||fail_n\  = PWRGD_CHJ_CPU1_DIMM
  HAS  = PD_CHJ_CPU1_DIMM_SAA
  RFU2  = NC
  RFU3  = NC
  VSS64  = GND
  DQ2_A  = M_J_CPU1_SA_DQ<2>
  VSS65  = GND
  DQ3_A  = M_J_CPU1_SA_DQ<3>
  VSS66  = GND
  \dqs5_a_c||tdqs5_a_c||dqs5_a_t||tdqs5_a_t\  = M_J_CPU1_SA_DQS_DN<5>
  \dqs5_a_t||tdqs5_a_t\  = M_J_CPU1_SA_DQS_DP<5>
  VSS67  = GND
  DQ6_A  = M_J_CPU1_SA_DQ<6>
  VSS68  = GND
  DQ7_A  = M_J_CPU1_SA_DQ<7>
  VSS69  = GND
  DQ10_A  = M_J_CPU1_SA_DQ<10>
  VSS70  = GND
  DQ11_A  = M_J_CPU1_SA_DQ<11>
  VSS71  = GND
  \dqs6_a_c||tdqs6_a_c||dqs6_a_t||tdqs6_a_t\  = M_J_CPU1_SA_DQS_DN<6>
  \dqs6_a_t||tdqs6_a_t\  = M_J_CPU1_SA_DQS_DP<6>
  VSS72  = GND
  DQ14_A  = M_J_CPU1_SA_DQ<14>
  VSS73  = GND
  DQ15_A  = M_J_CPU1_SA_DQ<15>
  VSS74  = GND
  DQ18_A  = M_J_CPU1_SA_DQ<18>
  VSS75  = GND
  DQ19_A  = M_J_CPU1_SA_DQ<19>
  VSS76  = GND
  \dqs7_a_c||tdqs7_a_c\  = M_J_CPU1_SA_DQS_DN<7>
  \dqs7_a_t||tdqs7_a_t\  = M_J_CPU1_SA_DQS_DP<7>
  VSS77  = GND
  DQ22_A  = M_J_CPU1_SA_DQ<22>
  VSS78  = GND
  DQ23_A  = M_J_CPU1_SA_DQ<23>
  VSS79  = GND
  DQ26_A  = M_J_CPU1_SA_DQ<26>
  VSS80  = GND
  DQ27_A  = M_J_CPU1_SA_DQ<27>
  VSS81  = GND
  \dqs8_a_c||tdqs8_a_c\  = M_J_CPU1_SA_DQS_DN<8>
  \dqs8_a_t||tdqs8_a_t\  = M_J_CPU1_SA_DQS_DP<8>
  VSS82  = GND
  DQ30_A  = M_J_CPU1_SA_DQ<30>
  VSS83  = GND
  DQ31_A  = M_J_CPU1_SA_DQ<31>
  VSS84  = GND
  CB2_A  = M_J_CPU1_SA_CB<2>
  VSS85  = GND
  CB3_A  = M_J_CPU1_SA_CB<3>
  VSS86  = GND
  \dqs9_a_c||tdqs9_a_c\  = M_J_CPU1_SA_DQS_DN<9>
  \dqs9_a_t||tdqs9_a_t\  = M_J_CPU1_SA_DQS_DP<9>
  VSS87  = GND
  CB6_A  = M_J_CPU1_SA_CB<6>
  VSS88  = GND
  CB7_A  = M_J_CPU1_SA_CB<7>
  VSS89  = GND
  RESET_N  = M_J_CPU1_RESET_N
  VSS90  = GND
  CS1_A_N  = M_J_CPU1_SA_CS_N<1>
  VSS91  = GND
  CA1_A  = M_J_CPU1_SA_CA<1>
  VSS92  = GND
  CA3_A  = M_J_CPU1_SA_CA<3>
  VSS93  = GND
  CA5_A  = M_J_CPU1_SA_CA<5>
  VSS94  = GND
  CK_T  = M_J_CPU1_CLK_DP<0>
  CK_C  = M_J_CPU1_CLK_DN<0>
  VSS95  = GND
  RFU4  = NC
  CA1_B  = M_J_CPU1_SB_CA<1>
  VSS96  = GND
  CA3_B  = M_J_CPU1_SB_CA<3>
  VSS97  = GND
  CA5_B  = M_J_CPU1_SB_CA<5>
  VSS98  = GND
  PAR_B  = M_J_CPU1_SB_PAR
  VSS99  = GND
  CS1_B_N  = M_J_CPU1_SB_CS_N<1>
  VSS100  = GND
  RFU5  = NC
  RFU6  = NC
  VSS101  = GND
  CB6_B  = M_J_CPU1_SB_CB<6>
  VSS102  = GND
  CB7_B  = M_J_CPU1_SB_CB<7>
  VSS103  = GND
  DQS4_B_C  = M_J_CPU1_SB_DQS_DN<4>
  DQS4_B_T  = M_J_CPU1_SB_DQS_DP<4>
  VSS104  = GND
  CB2_B  = M_J_CPU1_SB_CB<2>
  VSS105  = GND
  CB3_B  = M_J_CPU1_SB_CB<3>
  VSS106  = GND
  DQ2_B  = M_J_CPU1_SB_DQ<2>
  VSS107  = GND
  DQ3_B  = M_J_CPU1_SB_DQ<3>
  VSS108  = GND
  \dqs5_b_c||tdqs5_b_c\  = M_J_CPU1_SB_DQS_DN<5>
  \dqs5_b_t||tdqs5_b_t\  = M_J_CPU1_SB_DQS_DP<5>
  VSS109  = GND
  DQ6_B  = M_J_CPU1_SB_DQ<6>
  VSS110  = GND
  DQ7_B  = M_J_CPU1_SB_DQ<7>
  VSS111  = GND
  DQ10_B  = M_J_CPU1_SB_DQ<10>
  VSS112  = GND
  DQ11_B  = M_J_CPU1_SB_DQ<11>
  VSS113  = GND
  \dqs6_b_c||tdqs6_b_c\  = M_J_CPU1_SB_DQS_DN<6>
  \dqs6_b_t||tdqs6_b_t\  = M_J_CPU1_SB_DQS_DP<6>
  VSS114  = GND
  DQ14_B  = M_J_CPU1_SB_DQ<14>
  VSS115  = GND
  DQ15_B  = M_J_CPU1_SB_DQ<15>
  VSS116  = GND
  DQ18_B  = M_J_CPU1_SB_DQ<18>
  VSS117  = GND
  DQ19_B  = M_J_CPU1_SB_DQ<19>
  VSS118  = GND
  \dqs7_b_c||tdqs7_b_c\  = M_J_CPU1_SB_DQS_DN<7>
  \dqs7_b_t||tdqs7_b_t\  = M_J_CPU1_SB_DQS_DP<7>
  VSS119  = GND
  DQ22_B  = M_J_CPU1_SB_DQ<22>
  VSS120  = GND
  DQ23_B  = M_J_CPU1_SB_DQ<23>
  VSS121  = GND
  DQ26_B  = M_J_CPU1_SB_DQ<26>
  VSS122  = GND
  DQ27_B  = M_J_CPU1_SB_DQ<27>
  VSS123  = GND
  \dqs8_b_c||tdqs8_b_c\  = M_J_CPU1_SB_DQS_DN<8>
  \dqs8_b_t||tdqs8_b_t\  = M_J_CPU1_SB_DQS_DP<8>
  VSS124  = GND
  DQ30_B  = M_J_CPU1_SB_DQ<30>
  VSS125  = GND
  DQ31_B  = M_J_CPU1_SB_DQ<31>
  VSS126  = GND
  G1  = GND
  G2  = GND
  G3  = GND

(kicad_pcb
	(version 20260206)
	(generator "pcbnew")
	(generator_version "10.0")
	(general
		(thickness 1.6)
		(legacy_teardrops no)
	)
	(paper "A4")
	(title_block
		(title "04192023_DAF0TMB3IC0_F0TG_MB_C_brd_V02_OCP.brd")
		(comment 1 "Grand Teton / footprint 1456 of 8354 (J29), pads 184-229 of 291")
	)
	(layers
		(0 "F.Cu" signal "TOP")
		(4 "In1.Cu" signal "GND")
		(6 "In2.Cu" signal "IN1")
		(8 "In3.Cu" signal "GND1")
		(10 "In4.Cu" signal "IN2")
		(12 "In5.Cu" signal "GND2")
		(14 "In6.Cu" signal "IN3")
		(16 "In7.Cu" signal "GND3")
		(18 "In8.Cu" signal "VCC")
		(20 "In9.Cu" signal "VCC1")
		(22 "In10.Cu" signal "GND4")
		(24 "In11.Cu" signal "IN4")
		(26 "In12.Cu" signal "GND5")
		(28 "In13.Cu" signal "IN5")
		(30 "In14.Cu" signal "GND6")
		(32 "In15.Cu" signal "IN6")
		(34 "In16.Cu" signal "GND7")
		(2 "B.Cu" signal "BOTTOM")
		(9 "F.Adhes" user "F.Adhesive")
		(11 "B.Adhes" user "B.Adhesive")
		(13 "F.Paste" user "Package Geometry/Pastemask Top")
		(15 "B.Paste" user "Package Geometry/Pastemask Bottom")
		(5 "F.SilkS" user "Ref Des/Silkscreen Top")
		(7 "B.SilkS" user "Ref Des/Silkscreen Bottom")
		(1 "F.Mask" user "Board Geometry/Soldermask Top")
		(3 "B.Mask" user "Board Geometry/Soldermask Bottom")
		(17 "Dwgs.User" user "User.Drawings")
		(19 "Cmts.User" user "User.Comments")
		(21 "Eco1.User" user "User.Eco1")
		(23 "Eco2.User" user "User.Eco2")
		(25 "Edge.Cuts" user "Board Geometry/Outline")
		(27 "Margin" user)
		(31 "F.CrtYd" user "Package Geometry/Place Bound Top")
		(29 "B.CrtYd" user "Package Geometry/Place Bound Bottom")
		(35 "F.Fab" user "Ref Des/Assembly Top")
		(33 "B.Fab" user "Ref Des/Assembly Bottom")
	)
	(footprint ""
		(layer "F.Cu")
		(at 189.110112 -255.560322 180)
		(property "Reference" "J29"
			(at -2.7178 -81.857088 0)
			(unlocked yes)
			(layer "F.SilkS")
			(effects
				(font
					(size 0.7874 0.5842)
					(thickness 0.1524)
				)
			)
		)
		(property "Value" ""
			(at 0 0 180)
			(layer "F.Fab")
			(effects
				(font
					(size 1.27 1.27)
				)
			)
		)
		(duplicate_pad_numbers_are_jumpers no)
		(pad "184" smd rect
			(at 2.050034 -30.174946 90)
			(size 0.519938 1.4986)
			(layers "F.Cu" "F.Mask" "F.Paste")
			(net "GND")
		)
		(pad "185" smd rect
			(at 2.050034 -29.325062 90)
			(size 0.519938 1.4986)
			(layers "F.Cu" "F.Mask" "F.Paste")
			(net "M_J_CPU1_SA_DQ<26>")
		)
		(pad "186" smd rect
			(at 2.050034 -28.474924 90)
			(size 0.519938 1.4986)
			(layers "F.Cu" "F.Mask" "F.Paste")
			(net "GND")
		)
		(pad "187" smd rect
			(at 2.050034 -27.62504 90)
			(size 0.519938 1.4986)
			(layers "F.Cu" "F.Mask" "F.Paste")
			(net "M_J_CPU1_SA_DQ<27>")
		)
		(pad "188" smd rect
			(at 2.050034 -26.774902 90)
			(size 0.519938 1.4986)
			(layers "F.Cu" "F.Mask" "F.Paste")
			(net "GND")
		)
		(pad "189" smd rect
			(at 2.050034 -25.925018 90)
			(size 0.519938 1.4986)
			(layers "F.Cu" "F.Mask" "F.Paste")
			(net "M_J_CPU1_SA_DQS_DN<8>")
		)
		(pad "190" smd rect
			(at 2.050034 -25.07488 90)
			(size 0.519938 1.4986)
			(layers "F.Cu" "F.Mask" "F.Paste")
			(net "M_J_CPU1_SA_DQS_DP<8>")
		)
		(pad "191" smd rect
			(at 2.050034 -24.224996 90)
			(size 0.519938 1.4986)
			(layers "F.Cu" "F.Mask" "F.Paste")
			(net "GND")
		)
		(pad "192" smd rect
			(at 2.050034 -23.375112 90)
			(size 0.519938 1.4986)
			(layers "F.Cu" "F.Mask" "F.Paste")
			(net "M_J_CPU1_SA_DQ<30>")
		)
		(pad "193" smd rect
			(at 2.050034 -22.524974 90)
			(size 0.519938 1.4986)
			(layers "F.Cu" "F.Mask" "F.Paste")
			(net "GND")
		)
		(pad "194" smd rect
			(at 2.050034 -21.67509 90)
			(size 0.519938 1.4986)
			(layers "F.Cu" "F.Mask" "F.Paste")
			(net "M_J_CPU1_SA_DQ<31>")
		)
		(pad "195" smd rect
			(at 2.050034 -20.824952 90)
			(size 0.519938 1.4986)
			(layers "F.Cu" "F.Mask" "F.Paste")
			(net "GND")
		)
		(pad "196" smd rect
			(at 2.050034 -19.975068 90)
			(size 0.519938 1.4986)
			(layers "F.Cu" "F.Mask" "F.Paste")
			(net "M_J_CPU1_SA_CB<2>")
		)
		(pad "197" smd rect
			(at 2.050034 -19.12493 90)
			(size 0.519938 1.4986)
			(layers "F.Cu" "F.Mask" "F.Paste")
			(net "GND")
		)
		(pad "198" smd rect
			(at 2.050034 -18.275046 90)
			(size 0.519938 1.4986)
			(layers "F.Cu" "F.Mask" "F.Paste")
			(net "M_J_CPU1_SA_CB<3>")
		)
		(pad "199" smd rect
			(at 2.050034 -17.424908 90)
			(size 0.519938 1.4986)
			(layers "F.Cu" "F.Mask" "F.Paste")
			(net "GND")
		)
		(pad "200" smd rect
			(at 2.050034 -16.575024 90)
			(size 0.519938 1.4986)
			(layers "F.Cu" "F.Mask" "F.Paste")
			(net "M_J_CPU1_SA_DQS_DN<9>")
		)
		(pad "201" smd rect
			(at 2.050034 -15.724886 90)
			(size 0.519938 1.4986)
			(layers "F.Cu" "F.Mask" "F.Paste")
			(net "M_J_CPU1_SA_DQS_DP<9>")
		)
		(pad "202" smd rect
			(at 2.050034 -14.875002 90)
			(size 0.519938 1.4986)
			(layers "F.Cu" "F.Mask" "F.Paste")
			(net "GND")
		)
		(pad "203" smd rect
			(at 2.050034 -14.025118 90)
			(size 0.519938 1.4986)
			(layers "F.Cu" "F.Mask" "F.Paste")
			(net "M_J_CPU1_SA_CB<6>")
		)
		(pad "204" smd rect
			(at 2.050034 -13.17498 90)
			(size 0.519938 1.4986)
			(layers "F.Cu" "F.Mask" "F.Paste")
			(net "GND")
		)
		(pad "205" smd rect
			(at 2.050034 -12.325096 90)
			(size 0.519938 1.4986)
			(layers "F.Cu" "F.Mask" "F.Paste")
			(net "M_J_CPU1_SA_CB<7>")
		)
		(pad "206" smd rect
			(at 2.050034 -11.474958 90)
			(size 0.519938 1.4986)
			(layers "F.Cu" "F.Mask" "F.Paste")
			(net "GND")
		)
		(pad "207" smd rect
			(at 2.050034 -10.625074 90)
			(size 0.519938 1.4986)
			(layers "F.Cu" "F.Mask" "F.Paste")
			(net "M_J_CPU1_RESET_N")
		)
		(pad "208" smd rect
			(at 2.050034 -9.774936 90)
			(size 0.519938 1.4986)
			(layers "F.Cu" "F.Mask" "F.Paste")
			(net "GND")
		)
		(pad "209" smd rect
			(at 2.050034 -8.925052 90)
			(size 0.519938 1.4986)
			(layers "F.Cu" "F.Mask" "F.Paste")
			(net "M_J_CPU1_SA_CS_N<1>")
		)
		(pad "210" smd rect
			(at 2.050034 -8.074914 90)
			(size 0.519938 1.4986)
			(layers "F.Cu" "F.Mask" "F.Paste")
			(net "GND")
		)
		(pad "211" smd rect
			(at 2.050034 -7.22503 90)
			(size 0.519938 1.4986)
			(layers "F.Cu" "F.Mask" "F.Paste")
			(net "M_J_CPU1_SA_CA<1>")
		)
		(pad "212" smd rect
			(at 2.050034 -6.374892 90)
			(size 0.519938 1.4986)
			(layers "F.Cu" "F.Mask" "F.Paste")
			(net "GND")
		)
		(pad "213" smd rect
			(at 2.050034 -5.525008 90)
			(size 0.519938 1.4986)
			(layers "F.Cu" "F.Mask" "F.Paste")
			(net "M_J_CPU1_SA_CA<3>")
		)
		(pad "214" smd rect
			(at 2.050034 -4.675124 90)
			(size 0.519938 1.4986)
			(layers "F.Cu" "F.Mask" "F.Paste")
			(net "GND")
		)
		(pad "215" smd rect
			(at 2.050034 -3.824986 90)
			(size 0.519938 1.4986)
			(layers "F.Cu" "F.Mask" "F.Paste")
			(net "M_J_CPU1_SA_CA<5>")
		)
		(pad "216" smd rect
			(at 2.050034 -2.975102 90)
			(size 0.519938 1.4986)
			(layers "F.Cu" "F.Mask" "F.Paste")
			(net "GND")
		)
		(pad "217" smd rect
			(at 2.050034 -2.124964 90)
			(size 0.519938 1.4986)
			(layers "F.Cu" "F.Mask" "F.Paste")
			(net "M_J_CPU1_CLK_DP<0>")
		)
		(pad "218" smd rect
			(at 2.050034 -1.27508 90)
			(size 0.519938 1.4986)
			(layers "F.Cu" "F.Mask" "F.Paste")
			(net "M_J_CPU1_CLK_DN<0>")
		)
		(pad "219" smd rect
			(at 2.050034 -0.424942 90)
			(size 0.519938 1.4986)
			(layers "F.Cu" "F.Mask" "F.Paste")
			(net "GND")
		)
		(pad "220" smd rect
			(at 2.050034 5.525008 90)
			(size 0.519938 1.4986)
			(layers "F.Cu" "F.Mask" "F.Paste")
			(net "Net_2386")
		)
		(pad "221" smd rect
			(at 2.050034 6.374892 90)
			(size 0.519938 1.4986)
			(layers "F.Cu" "F.Mask" "F.Paste")
			(net "M_J_CPU1_SB_CA<1>")
		)
		(pad "222" smd rect
			(at 2.050034 7.22503 90)
			(size 0.519938 1.4986)
			(layers "F.Cu" "F.Mask" "F.Paste")
			(net "GND")
		)
		(pad "223" smd rect
			(at 2.050034 8.074914 90)
			(size 0.519938 1.4986)
			(layers "F.Cu" "F.Mask" "F.Paste")
			(net "M_J_CPU1_SB_CA<3>")
		)
		(pad "224" smd rect
			(at 2.050034 8.925052 90)
			(size 0.519938 1.4986)
			(layers "F.Cu" "F.Mask" "F.Paste")
			(net "GND")
		)
		(pad "225" smd rect
			(at 2.050034 9.774936 90)
			(size 0.519938 1.4986)
			(layers "F.Cu" "F.Mask" "F.Paste")
			(net "M_J_CPU1_SB_CA<5>")
		)
		(pad "226" smd rect
			(at 2.050034 10.625074 90)
			(size 0.519938 1.4986)
			(layers "F.Cu" "F.Mask" "F.Paste")
			(net "GND")
		)
		(pad "227" smd rect
			(at 2.050034 11.474958 90)
			(size 0.519938 1.4986)
			(layers "F.Cu" "F.Mask" "F.Paste")
			(net "M_J_CPU1_SB_PAR")
		)
		(pad "228" smd rect
			(at 2.050034 12.325096 90)
			(size 0.519938 1.4986)
			(layers "F.Cu" "F.Mask" "F.Paste")
			(net "GND")
		)
		(pad "229" smd rect
			(at 2.050034 13.17498 90)
			(size 0.519938 1.4986)
			(layers "F.Cu" "F.Mask" "F.Paste")
			(net "M_J_CPU1_SB_CS_N<1>")
		)
	)
)
